# S9S_MB_2U (Grand Teton) — schematic netlist excerpt (pin names and nets, part order shuffled) for the footprints in the layout excerpt that follows; sources: Cadence DE-HDL packaged netlist, KiCad conversion of 03242023_DA0F0TMBIJ0_F0T_Motherboard_J_brd_V01_OCP.brd

R4411  Q_RES  4.75K 1% CHIP  pkg 0402LF  page 123 : A = P3V3 ; B = H_CPU0_MEMTRIP_VT_N
R4586  Q_RES  10K 1% CHIP  pkg 0402LF  page 195 : A = P3V3_AUX ; B = FAB_BMC_REV_ID2

(kicad_pcb
	(version 20260206)
	(generator "pcbnew")
	(generator_version "10.0")
	(general
		(thickness 1.6)
		(legacy_teardrops no)
	)
	(paper "A4")
	(title_block
		(title "03242023_DA0F0TMBIJ0_F0T_Motherboard_J_brd_V01_OCP.brd")
		(comment 1 "Grand Teton / footprints 2410-2411 of 6105")
	)
	(layers
		(0 "F.Cu" signal "TOP")
		(4 "In1.Cu" signal "GND")
		(6 "In2.Cu" signal "IN1")
		(8 "In3.Cu" signal "GND1")
		(10 "In4.Cu" signal "IN2")
		(12 "In5.Cu" signal "GND2")
		(14 "In6.Cu" signal "IN3")
		(16 "In7.Cu" signal "GND3")
		(18 "In8.Cu" signal "VCC")
		(20 "In9.Cu" signal "VCC1")
		(22 "In10.Cu" signal "GND4")
		(24 "In11.Cu" signal "IN4")
		(26 "In12.Cu" signal "GND5")
		(28 "In13.Cu" signal "IN5")
		(30 "In14.Cu" signal "GND6")
		(32 "In15.Cu" signal "IN6")
		(34 "In16.Cu" signal "GND7")
		(2 "B.Cu" signal "BOTTOM")
		(9 "F.Adhes" user "F.Adhesive")
		(11 "B.Adhes" user "B.Adhesive")
		(13 "F.Paste" user "Package Geometry/Pastemask Top")
		(15 "B.Paste" user "Package Geometry/Pastemask Bottom")
		(5 "F.SilkS" user "Ref Des/Silkscreen Top")
		(7 "B.SilkS" user "Ref Des/Silkscreen Bottom")
		(1 "F.Mask" user "Board Geometry/Soldermask Top")
		(3 "B.Mask" user "Board Geometry/Soldermask Bottom")
		(17 "Dwgs.User" user "User.Drawings")
		(19 "Cmts.User" user "User.Comments")
		(21 "Eco1.User" user "User.Eco1")
		(23 "Eco2.User" user "User.Eco2")
		(25 "Edge.Cuts" user "Board Geometry/Outline")
		(27 "Margin" user)
		(31 "F.CrtYd" user "Package Geometry/Place Bound Top")
		(29 "B.CrtYd" user "Package Geometry/Place Bound Bottom")
		(35 "F.Fab" user "Ref Des/Assembly Top")
		(33 "B.Fab" user "Ref Des/Assembly Bottom")
	)
	(footprint ""
		(layer "F.Cu")
		(at 130.48488 -100.167948 90)
		(property "Reference" "R4411"
			(at 0 0 90)
			(layer "F.SilkS")
			(hide yes)
			(effects
				(font
					(size 1.27 1.27)
				)
			)
		)
		(property "Value" ""
			(at 0 0 90)
			(layer "F.Fab")
			(effects
				(font
					(size 1.27 1.27)
				)
			)
		)
		(duplicate_pad_numbers_are_jumpers no)
		(fp_line
			(start 0.7874 -0.4064)
			(end 0.7874 0.4064)
			(stroke
				(width 0.1524)
				(type default)
			)
			(layer "F.SilkS")
		)
		(fp_line
			(start -0.7874 -0.4064)
			(end 0.7874 -0.4064)
			(stroke
				(width 0.1524)
				(type default)
			)
			(layer "F.SilkS")
		)
		(fp_line
			(start 0.7874 0.4064)
			(end -0.7874 0.4064)
			(stroke
				(width 0.1524)
				(type default)
			)
			(layer "F.SilkS")
		)
		(fp_line
			(start -0.7874 0.4064)
			(end -0.7874 -0.4064)
			(stroke
				(width 0.1524)
				(type default)
			)
			(layer "F.SilkS")
		)
		(fp_line
			(start -0.12065 -0.305054)
			(end -0.12065 -0.2794)
			(stroke
				(width 0.1)
				(type default)
			)
			(layer "F.Fab")
		)
		(fp_line
			(start -0.67945 -0.305054)
			(end -0.12065 -0.305054)
			(stroke
				(width 0.1)
				(type default)
			)
			(layer "F.Fab")
		)
		(fp_line
			(start 0.67945 -0.3048)
			(end 0.67945 0.3048)
			(stroke
				(width 0.1)
				(type default)
			)
			(layer "F.Fab")
		)
		(fp_line
			(start 0.12065 -0.3048)
			(end 0.67945 -0.3048)
			(stroke
				(width 0.1)
				(type default)
			)
			(layer "F.Fab")
		)
		(fp_line
			(start 0.12065 -0.2794)
			(end 0.12065 -0.3048)
			(stroke
				(width 0.1)
				(type default)
			)
			(layer "F.Fab")
		)
		(fp_line
			(start -0.12065 -0.2794)
			(end 0.12065 -0.2794)
			(stroke
				(width 0.1)
				(type default)
			)
			(layer "F.Fab")
		)
		(fp_line
			(start 0.120396 0.2794)
			(end -0.12065 0.2794)
			(stroke
				(width 0.1)
				(type default)
			)
			(layer "F.Fab")
		)
		(fp_line
			(start -0.12065 0.2794)
			(end -0.12065 0.3048)
			(stroke
				(width 0.1)
				(type default)
			)
			(layer "F.Fab")
		)
		(fp_line
			(start 0.67945 0.3048)
			(end 0.120396 0.3048)
			(stroke
				(width 0.1)
				(type default)
			)
			(layer "F.Fab")
		)
		(fp_line
			(start 0.120396 0.3048)
			(end 0.120396 0.2794)
			(stroke
				(width 0.1)
				(type default)
			)
			(layer "F.Fab")
		)
		(fp_line
			(start -0.12065 0.3048)
			(end -0.67945 0.3048)
			(stroke
				(width 0.1)
				(type default)
			)
			(layer "F.Fab")
		)
		(fp_line
			(start -0.67945 0.3048)
			(end -0.67945 -0.305054)
			(stroke
				(width 0.1)
				(type default)
			)
			(layer "F.Fab")
		)
		(pad "1" smd circle
			(at -0.40005 0 90)
			(size 0 0)
			(layers "F.Cu" "F.Mask" "F.Paste")
			(net "P3V3")
		)
		(pad "2" smd circle
			(at 0.40005 0 90)
			(size 0 0)
			(layers "F.Cu" "F.Mask" "F.Paste")
			(net "H_CPU0_MEMTRIP_VT_N")
		)
	)
	(footprint ""
		(layer "F.Cu")
		(at 176.6824 -93.538548 90)
		(property "Reference" "R4586"
			(at 0 0 90)
			(layer "F.SilkS")
			(hide yes)
			(effects
				(font
					(size 1.27 1.27)
				)
			)
		)
		(property "Value" ""
			(at 0 0 90)
			(layer "F.Fab")
			(effects
				(font
					(size 1.27 1.27)
				)
			)
		)
		(duplicate_pad_numbers_are_jumpers no)
		(fp_line
			(start 0.7874 -0.4064)
			(end 0.7874 0.4064)
			(stroke
				(width 0.1524)
				(type default)
			)
			(layer "F.SilkS")
		)
		(fp_line
			(start -0.7874 -0.4064)
			(end 0.7874 -0.4064)
			(stroke
				(width 0.1524)
				(type default)
			)
			(layer "F.SilkS")
		)
		(fp_line
			(start 0.7874 0.4064)
			(end -0.7874 0.4064)
			(stroke
				(width 0.1524)
				(type default)
			)
			(layer "F.SilkS")
		)
		(fp_line
			(start -0.7874 0.4064)
			(end -0.7874 -0.4064)
			(stroke
				(width 0.1524)
				(type default)
			)
			(layer "F.SilkS")
		)
		(fp_line
			(start -0.12065 -0.305054)
			(end -0.12065 -0.2794)
			(stroke
				(width 0.1)
				(type default)
			)
			(layer "F.Fab")
		)
		(fp_line
			(start -0.67945 -0.305054)
			(end -0.12065 -0.305054)
			(stroke
				(width 0.1)
				(type default)
			)
			(layer "F.Fab")
		)
		(fp_line
			(start 0.67945 -0.3048)
			(end 0.67945 0.3048)
			(stroke
				(width 0.1)
				(type default)
			)
			(layer "F.Fab")
		)
		(fp_line
			(start 0.12065 -0.3048)
			(end 0.67945 -0.3048)
			(stroke
				(width 0.1)
				(type default)
			)
			(layer "F.Fab")
		)
		(fp_line
			(start 0.12065 -0.2794)
			(end 0.12065 -0.3048)
			(stroke
				(width 0.1)
				(type default)
			)
			(layer "F.Fab")
		)
		(fp_line
			(start -0.12065 -0.2794)
			(end 0.12065 -0.2794)
			(stroke
				(width 0.1)
				(type default)
			)
			(layer "F.Fab")
		)
		(fp_line
			(start 0.120396 0.2794)
			(end -0.12065 0.2794)
			(stroke
				(width 0.1)
				(type default)
			)
			(layer "F.Fab")
		)
		(fp_line
			(start -0.12065 0.2794)
			(end -0.12065 0.3048)
			(stroke
				(width 0.1)
				(type default)
			)
			(layer "F.Fab")
		)
		(fp_line
			(start 0.67945 0.3048)
			(end 0.120396 0.3048)
			(stroke
				(width 0.1)
				(type default)
			)
			(layer "F.Fab")
		)
		(fp_line
			(start 0.120396 0.3048)
			(end 0.120396 0.2794)
			(stroke
				(width 0.1)
				(type default)
			)
			(layer "F.Fab")
		)
		(fp_line
			(start -0.12065 0.3048)
			(end -0.67945 0.3048)
			(stroke
				(width 0.1)
				(type default)
			)
			(layer "F.Fab")
		)
		(fp_line
			(start -0.67945 0.3048)
			(end -0.67945 -0.305054)
			(stroke
				(width 0.1)
				(type default)
			)
			(layer "F.Fab")
		)
		(pad "1" smd rect
			(at -0.40005 0 270)
			(size 0.4572 0.508)
			(layers "F.Cu" "F.Mask" "F.Paste")
			(net "P3V3_AUX")
		)
		(pad "2" smd rect
			(at 0.40005 0 270)
			(size 0.4572 0.508)
			(layers "F.Cu" "F.Mask" "F.Paste")
			(net "FAB_BMC_REV_ID2")
		)
	)
)
